# SCM (Grand Teton) — schematic netlist excerpt (pin names and nets, part order shuffled) for the footprints in the layout excerpt that follows; sources: Cadence DE-HDL packaged netlist, KiCad conversion of 12092022_DA0F0TMDCD0_F0T_Management_Board_D_brd_V3_OCP.brd

R66  Q_RES  100K 1% CHIP  pkg 0402LF  page 11 : A = GND ; B = PWRGD_PSU_AC_PWROK
R33  Q_RES  33.2 1% CHIP  pkg 0402LF  page 46 : A = SMB_BMC_MM16_R5_SDA ; B = SMB_BMC_TPM_MM16_SDA

(kicad_pcb
	(version 20260206)
	(generator "pcbnew")
	(generator_version "10.0")
	(general
		(thickness 1.6)
		(legacy_teardrops no)
	)
	(paper "A4")
	(title_block
		(title "12092022_DA0F0TMDCD0_F0T_Management_Board_D_brd_V3_OCP.brd")
		(comment 1 "Grand Teton / footprints 194-195 of 1440")
	)
	(layers
		(0 "F.Cu" signal "TOP")
		(4 "In1.Cu" signal "GND")
		(6 "In2.Cu" signal "IN1")
		(8 "In3.Cu" signal "GND1")
		(10 "In4.Cu" signal "IN2")
		(12 "In5.Cu" signal "VCC")
		(14 "In6.Cu" signal "VCC1")
		(16 "In7.Cu" signal "IN3")
		(18 "In8.Cu" signal "GND2")
		(20 "In9.Cu" signal "IN4")
		(22 "In10.Cu" signal "GND3")
		(2 "B.Cu" signal "BOTTOM")
		(9 "F.Adhes" user "F.Adhesive")
		(11 "B.Adhes" user "B.Adhesive")
		(13 "F.Paste" user "Package Geometry/Pastemask Top")
		(15 "B.Paste" user "Package Geometry/Pastemask Bottom")
		(5 "F.SilkS" user "Ref Des/Silkscreen Top")
		(7 "B.SilkS" user "Ref Des/Silkscreen Bottom")
		(1 "F.Mask" user "Board Geometry/Soldermask Top")
		(3 "B.Mask" user "Board Geometry/Soldermask Bottom")
		(17 "Dwgs.User" user "User.Drawings")
		(19 "Cmts.User" user "User.Comments")
		(21 "Eco1.User" user "User.Eco1")
		(23 "Eco2.User" user "User.Eco2")
		(25 "Edge.Cuts" user "Board Geometry/Outline")
		(27 "Margin" user)
		(31 "F.CrtYd" user "Package Geometry/Place Bound Top")
		(29 "B.CrtYd" user "Package Geometry/Place Bound Bottom")
		(35 "F.Fab" user "Ref Des/Assembly Top")
		(33 "B.Fab" user "Ref Des/Assembly Bottom")
	)
	(footprint ""
		(layer "F.Cu")
		(at 73.980294 -99.4664)
		(property "Reference" "R33"
			(at 0 0 0)
			(layer "F.SilkS")
			(hide yes)
			(effects
				(font
					(size 1.27 1.27)
				)
			)
		)
		(property "Value" ""
			(at 0 0 0)
			(layer "F.Fab")
			(effects
				(font
					(size 1.27 1.27)
				)
			)
		)
		(duplicate_pad_numbers_are_jumpers no)
		(fp_line
			(start -0.7874 -0.4064)
			(end 0.7874 -0.4064)
			(stroke
				(width 0.1524)
				(type default)
			)
			(layer "F.SilkS")
		)
		(fp_line
			(start -0.7874 0.4064)
			(end -0.7874 -0.4064)
			(stroke
				(width 0.1524)
				(type default)
			)
			(layer "F.SilkS")
		)
		(fp_line
			(start 0.7874 -0.4064)
			(end 0.7874 0.4064)
			(stroke
				(width 0.1524)
				(type default)
			)
			(layer "F.SilkS")
		)
		(fp_line
			(start 0.7874 0.4064)
			(end -0.7874 0.4064)
			(stroke
				(width 0.1524)
				(type default)
			)
			(layer "F.SilkS")
		)
		(fp_line
			(start -0.67945 -0.305054)
			(end -0.12065 -0.305054)
			(stroke
				(width 0.1)
				(type default)
			)
			(layer "F.Fab")
		)
		(fp_line
			(start -0.67945 0.3048)
			(end -0.67945 -0.305054)
			(stroke
				(width 0.1)
				(type default)
			)
			(layer "F.Fab")
		)
		(fp_line
			(start -0.12065 -0.305054)
			(end -0.12065 -0.2794)
			(stroke
				(width 0.1)
				(type default)
			)
			(layer "F.Fab")
		)
		(fp_line
			(start -0.12065 -0.2794)
			(end 0.12065 -0.2794)
			(stroke
				(width 0.1)
				(type default)
			)
			(layer "F.Fab")
		)
		(fp_line
			(start -0.12065 0.2794)
			(end -0.12065 0.3048)
			(stroke
				(width 0.1)
				(type default)
			)
			(layer "F.Fab")
		)
		(fp_line
			(start -0.12065 0.3048)
			(end -0.67945 0.3048)
			(stroke
				(width 0.1)
				(type default)
			)
			(layer "F.Fab")
		)
		(fp_line
			(start 0.120396 0.2794)
			(end -0.12065 0.2794)
			(stroke
				(width 0.1)
				(type default)
			)
			(layer "F.Fab")
		)
		(fp_line
			(start 0.120396 0.3048)
			(end 0.120396 0.2794)
			(stroke
				(width 0.1)
				(type default)
			)
			(layer "F.Fab")
		)
		(fp_line
			(start 0.12065 -0.3048)
			(end 0.67945 -0.3048)
			(stroke
				(width 0.1)
				(type default)
			)
			(layer "F.Fab")
		)
		(fp_line
			(start 0.12065 -0.2794)
			(end 0.12065 -0.3048)
			(stroke
				(width 0.1)
				(type default)
			)
			(layer "F.Fab")
		)
		(fp_line
			(start 0.67945 -0.3048)
			(end 0.67945 0.3048)
			(stroke
				(width 0.1)
				(type default)
			)
			(layer "F.Fab")
		)
		(fp_line
			(start 0.67945 0.3048)
			(end 0.120396 0.3048)
			(stroke
				(width 0.1)
				(type default)
			)
			(layer "F.Fab")
		)
		(pad "1" smd circle
			(at -0.40005 0)
			(size 0 0)
			(layers "F.Cu" "F.Mask" "F.Paste")
			(net "SMB_BMC_MM16_R5_SDA")
		)
		(pad "2" smd circle
			(at 0.40005 0)
			(size 0 0)
			(layers "F.Cu" "F.Mask" "F.Paste")
			(net "SMB_BMC_TPM_MM16_SDA")
		)
	)
	(footprint ""
		(layer "F.Cu")
		(at 4.6736 -83.4644 180)
		(property "Reference" "R66"
			(at 0 0 180)
			(layer "F.SilkS")
			(hide yes)
			(effects
				(font
					(size 1.27 1.27)
				)
			)
		)
		(property "Value" ""
			(at 0 0 180)
			(layer "F.Fab")
			(effects
				(font
					(size 1.27 1.27)
				)
			)
		)
		(duplicate_pad_numbers_are_jumpers no)
		(fp_line
			(start 0.7874 0.4064)
			(end -0.7874 0.4064)
			(stroke
				(width 0.1524)
				(type default)
			)
			(layer "F.SilkS")
		)
		(fp_line
			(start 0.7874 -0.4064)
			(end 0.7874 0.4064)
			(stroke
				(width 0.1524)
				(type default)
			)
			(layer "F.SilkS")
		)
		(fp_line
			(start -0.7874 0.4064)
			(end -0.7874 -0.4064)
			(stroke
				(width 0.1524)
				(type default)
			)
			(layer "F.SilkS")
		)
		(fp_line
			(start -0.7874 -0.4064)
			(end 0.7874 -0.4064)
			(stroke
				(width 0.1524)
				(type default)
			)
			(layer "F.SilkS")
		)
		(fp_line
			(start 0.67945 0.3048)
			(end 0.120396 0.3048)
			(stroke
				(width 0.1)
				(type default)
			)
			(layer "F.Fab")
		)
		(fp_line
			(start 0.67945 -0.3048)
			(end 0.67945 0.3048)
			(stroke
				(width 0.1)
				(type default)
			)
			(layer "F.Fab")
		)
		(fp_line
			(start 0.12065 -0.2794)
			(end 0.12065 -0.3048)
			(stroke
				(width 0.1)
				(type default)
			)
			(layer "F.Fab")
		)
		(fp_line
			(start 0.12065 -0.3048)
			(end 0.67945 -0.3048)
			(stroke
				(width 0.1)
				(type default)
			)
			(layer "F.Fab")
		)
		(fp_line
			(start 0.120396 0.3048)
			(end 0.120396 0.2794)
			(stroke
				(width 0.1)
				(type default)
			)
			(layer "F.Fab")
		)
		(fp_line
			(start 0.120396 0.2794)
			(end -0.12065 0.2794)
			(stroke
				(width 0.1)
				(type default)
			)
			(layer "F.Fab")
		)
		(fp_line
			(start -0.12065 0.3048)
			(end -0.67945 0.3048)
			(stroke
				(width 0.1)
				(type default)
			)
			(layer "F.Fab")
		)
		(fp_line
			(start -0.12065 0.2794)
			(end -0.12065 0.3048)
			(stroke
				(width 0.1)
				(type default)
			)
			(layer "F.Fab")
		)
		(fp_line
			(start -0.12065 -0.2794)
			(end 0.12065 -0.2794)
			(stroke
				(width 0.1)
				(type default)
			)
			(layer "F.Fab")
		)
		(fp_line
			(start -0.12065 -0.305054)
			(end -0.12065 -0.2794)
			(stroke
				(width 0.1)
				(type default)
			)
			(layer "F.Fab")
		)
		(fp_line
			(start -0.67945 0.3048)
			(end -0.67945 -0.305054)
			(stroke
				(width 0.1)
				(type default)
			)
			(layer "F.Fab")
		)
		(fp_line
			(start -0.67945 -0.305054)
			(end -0.12065 -0.305054)
			(stroke
				(width 0.1)
				(type default)
			)
			(layer "F.Fab")
		)
		(pad "1" smd circle
			(at -0.40005 0 180)
			(size 0 0)
			(layers "F.Cu" "F.Mask" "F.Paste")
			(net "GND")
		)
		(pad "2" smd circle
			(at 0.40005 0 180)
			(size 0 0)
			(layers "F.Cu" "F.Mask" "F.Paste")
			(net "PWRGD_PSU_AC_PWROK")
		)
	)
)
